# BASEBOARD_FAB2 (Tioga Pass) — schematic parts with pin connectivity, parts 332–488 of 4751; source: Cadence DE-HDL packaged netlist (pstxprt.dat, pstxnet.dat, pstchip.dat)

C2G13  CAP_A  47UF 4V 20% X5R  pkg 0603V  page 225 : 1 = PVDDQ_GHJ ; 2 = GND
C2G14  CAP_A  47UF 4V 20% X5R  pkg 0603V  page 225 : 1 = PVDDQ_GHJ ; 2 = GND
C2G15  CAP_A  47UF 4V 20% X5R  pkg 0603V  page 225 : 1 = PVDDQ_GHJ ; 2 = GND
C2G16  CAP  100UF 4V 20% X5R  pkg 0805  page 225 : 1 = PVDDQ_GHJ ; 2 = GND
C2L2  CAP  220PF 50V 10% X7R  pkg 0402LF  page 235 : 1 = VR_P1V05_PCH_STBY_AVSP ; 2 = VSENSE_P1V05_PCH_STBY_AVSN
C2L3  CAP_A  0.01UF 25V 10% X7R  pkg 0402V  page 173 : 1 = SATA6G_PCH_PCIE_UP_SATA_RXN<3> ; 2 = SATA6G_P3_RX_C_DN
C2L4  CAP_A  0.01UF 25V 10% X7R  pkg 0402V  page 173 : 1 = SATA6G_PCH_PCIE_UP_SATA_RXP<3> ; 2 = SATA6G_P3_RX_C_DP
C2L5  CAP_A  0.01UF 25V 10% X7R  pkg 0402V  page 173 : 1 = SATA6G_PCH_PCIE_UP_SATA_RXN<7> ; 2 = SATA6G_P7_RX_C_DN
C2L6  CAP_A  0.01UF 25V 10% X7R  pkg 0402V  page 173 : 1 = SATA6G_PCH_PCIE_UP_SATA_RXN<1> ; 2 = SATA6G_P1_RX_C_DN
C2L7  CAP_A  0.01UF 25V 10% X7R  pkg 0402V  page 173 : 1 = SATA6G_PCH_PCIE_UP_SATA_RXP<7> ; 2 = SATA6G_P7_RX_C_DP
C2L8  CAP_A  1.0UF 6.3V 10% X6S  pkg 0402V  page 235 : 1 = VR_PVNN_PCH_VDD ; 2 = GND
C2L9  CAP_A  0.01UF 25V 10% X7R  pkg 0402V  page 173 : 1 = SATA6G_PCH_PCIE_UP_SATA_RXN<5> ; 2 = SATA6G_P5_RX_C_DN
C2L10  CAP_A  0.01UF 25V 10% X7R  pkg 0402V  page 173 : 1 = SATA6G_PCH_PCIE_UP_SATA_RXP<1> ; 2 = SATA6G_P1_RX_C_DP
C2L11  CAP_A  0.1UF 16V 10% X7R  pkg 0402V  page 235 : 1 = VR_PVNN_PCH_VDD ; 2 = GND
C2L12  CAP_A  0.01UF 25V 10% X7R  pkg 0402V  page 173 : 1 = SATA6G_PCH_PCIE_UP_SATA_RXP<5> ; 2 = SATA6G_P5_RX_C_DP
C2L13  CAP_A  0.01UF 25V 10% X7R  pkg 0402V  page 173 : 1 = SATA6G_PCH_PCIE_UP_SATA_RXN<2> ; 2 = SATA6G_P2_RX_C_DN
C2L14  CAP_A  0.01UF 25V 10% X7R  pkg 0402V  page 173 : 1 = SATA6G_PCH_PCIE_UP_SATA_RXN<6> ; 2 = SATA6G_P6_RX_C_DN
C2L15  CAP_A  0.01UF 25V 10% X7R  pkg 0402V  page 173 : 1 = SATA6G_PCH_PCIE_UP_SATA_RXP<2> ; 2 = SATA6G_P2_RX_C_DP
C2L16  CAP_A  0.01UF 25V 10% X7R  pkg 0402V  page 173 : 1 = SATA6G_PCH_PCIE_UP_SATA_RXP<6> ; 2 = SATA6G_P6_RX_C_DP
C2L17  CAP_A  0.01UF 25V 10% X7R  pkg 0402V  page 173 : 1 = SATA6G_PCH_PCIE_UP_SATA_RXN<0> ; 2 = SATA6G_P0_RX_C_DN
C2L18  CAP_A  0.01UF 25V 10% X7R  pkg 0402V  page 173 : 1 = SATA6G_PCH_PCIE_UP_SATA_RXN<4> ; 2 = SATA6G_P4_RX_C_DN
C2L19  CAP_A  0.01UF 25V 10% X7R  pkg 0402V  page 173 : 1 = SATA6G_PCH_PCIE_UP_SATA_RXP<0> ; 2 = SATA6G_P0_RX_C_DP
C2L20  CAP_A  0.01UF 25V 10% X7R  pkg 0402V  page 173 : 1 = SATA6G_PCH_PCIE_UP_SATA_RXP<4> ; 2 = SATA6G_P4_RX_C_DP
C2L21  CAP_A  0.01UF 25V 10% X7R  pkg 0402V  page 173 : 1 = SATA6G_P7_TX_C_DN ; 2 = SATA6G_PCH_PCIE_UP_SATA_TXN<7>
C2L22  CAP_A  0.01UF 25V 10% X7R  pkg 0402V  page 173 : 1 = SATA6G_P3_TX_C_DN ; 2 = SATA6G_PCH_PCIE_UP_SATA_TXN<3>
C2L23  CAP_A  0.01UF 25V 10% X7R  pkg 0402V  page 173 : 1 = SATA6G_P3_TX_C_DP ; 2 = SATA6G_PCH_PCIE_UP_SATA_TXP<3>
C2L24  CAP_A  0.01UF 25V 10% X7R  pkg 0402V  page 173 : 1 = SATA6G_P7_TX_C_DP ; 2 = SATA6G_PCH_PCIE_UP_SATA_TXP<7>
C2L25  CAPP  470UF 2V 20% ALUM  pkg SM  page 236 : 1 = P1V05_PCH_STBY ; 2 = GND
C2L26  CAP_A  0.01UF 25V 10% X7R  pkg 0402V  page 173 : 1 = SATA6G_P5_TX_C_DN ; 2 = SATA6G_PCH_PCIE_UP_SATA_TXN<5>
C2L27  CAP_A  0.01UF 25V 10% X7R  pkg 0402V  page 173 : 1 = SATA6G_P5_TX_C_DP ; 2 = SATA6G_PCH_PCIE_UP_SATA_TXP<5>
C2L32  CAP  47UF 4V 20% X6S  pkg 0805  page 237 : 1 = P1V8_PCH_STBY ; 2 = GND
C2L37  CAP_A  0.01UF 25V 10% X7R  pkg 0402V  page 173 : 1 = SATA6G_P4_TX_C_DN ; 2 = SATA6G_PCH_PCIE_UP_SATA_TXN<4>
C2L38  CAP_A  0.01UF 25V 10% X7R  pkg 0402V  page 173 : 1 = SATA6G_P6_TX_C_DN ; 2 = SATA6G_PCH_PCIE_UP_SATA_TXN<6>
C2L39  CAP_A  0.01UF 25V 10% X7R  pkg 0402V  page 173 : 1 = SATA6G_P0_TX_C_DP ; 2 = SATA6G_PCH_PCIE_UP_SATA_TXP<0>
C2L40  CAP_A  0.01UF 25V 10% X7R  pkg 0402V  page 173 : 1 = SATA6G_P0_TX_C_DN ; 2 = SATA6G_PCH_PCIE_UP_SATA_TXN<0>
C2L41  CAP_A  0.01UF 25V 10% X7R  pkg 0402V  page 173 : 1 = SATA6G_P2_TX_C_DP ; 2 = SATA6G_PCH_PCIE_UP_SATA_TXP<2>
C2L42  CAP_A  0.01UF 25V 10% X7R  pkg 0402V  page 173 : 1 = SATA6G_P2_TX_C_DN ; 2 = SATA6G_PCH_PCIE_UP_SATA_TXN<2>
C2L43  CAP_A  0.01UF 25V 10% X7R  pkg 0402V  page 173 : 1 = SATA6G_P1_TX_C_DP ; 2 = SATA6G_PCH_PCIE_UP_SATA_TXP<1>
C2L44  CAP_A  0.01UF 25V 10% X7R  pkg 0402V  page 173 : 1 = SATA6G_P1_TX_C_DN ; 2 = SATA6G_PCH_PCIE_UP_SATA_TXN<1>
C2L45  CAP  22UF 6.3V 20% X6S  pkg 0805  page 237 : 1 = P1V8_PCH_STBY ; 2 = GND
C2L46  CAPP  470UF 2V 20% ALUM  pkg SM  page 236 : 1 = P1V05_PCH_STBY ; 2 = GND
C2L47  CAP_A  0.01UF 25V 10% X7R  pkg 0402V  page 173 : 1 = SATA6G_P4_TX_C_DP ; 2 = SATA6G_PCH_PCIE_UP_SATA_TXP<4>
C2L48  CAP_A  0.01UF 25V 10% X7R  pkg 0402V  page 173 : 1 = SATA6G_P6_TX_C_DP ; 2 = SATA6G_PCH_PCIE_UP_SATA_TXP<6>
C2L49  CAP_A  0.01UF 25V 10% X7R  pkg 0402V  page 172 : 1 = SATA6G_S1_RX_C_DP ; 2 = SATA6G_S1_RX_DP
C2L50  CAP_A  0.01UF 25V 10% X7R  pkg 0402V  page 172 : 1 = SATA6G_S1_RX_C_DN ; 2 = SATA6G_S1_RX_DN
C2L51  CAP_A  0.01UF 25V 10% X7R  pkg 0402V  page 172 : 1 = SATA6G_S1_TX_C_DN ; 2 = SATA6G_S1_TX_DN
C2L52  CAP_A  0.01UF 25V 10% X7R  pkg 0402V  page 172 : 1 = SATA6G_S1_TX_C_DP ; 2 = SATA6G_S1_TX_DP
C2M1  CAP_A  22.0UF 4V 20% X6S  pkg 0603V  page 130 : 1 = P1V8_PCH_STBY ; 2 = GND
C2M2  CAP_A  22.0UF 4V 20% X6S  pkg 0603V  page 130 : 1 = P1V8_PCH_STBY ; 2 = GND
C2M3  CAP_A  0.1UF 16V 10% X7R  pkg 0402V  page 116 : 1 = P2E_SSB_BMC_TX_DN ; 2 = P2E_SSB_BMC_TX_C_DN
C2M4  CAP_A  0.1UF 16V 10% X7R  pkg 0402V  page 116 : 1 = P2E_SSB_BMC_TX_DP ; 2 = P2E_SSB_BMC_TX_C_DP
C2M5  CAP  10UF 4V 20% X6S  pkg 0603LF  page 127 : 1 = P1V05_PCH_STBY_WM20_PLL ; 2 = GND
C2M6  CAP_A  1.0UF 6.3V 10% X6S  pkg 0402V  page 127 : 1 = P1V05_PCH_STBY ; 2 = GND
C2M7  CAP_A  1.0UF 6.3V 10% X6S  pkg 0402V  page 127 : 1 = P1V05_PCH_STBY_WM20_PLL ; 2 = GND
C2M8  CAP_A  1.0UF 6.3V 10% X6S  pkg 0402V  page 127 : 1 = P1V05_PCH_STBY ; 2 = GND
C2M9  CAP_A  1.0UF 6.3V 10% X6S  pkg 0402V  page 127 : 1 = P1V05_PCH_STBY_WM26_PLL ; 2 = GND
C2M10  CAP  10UF 4V 20% X6S  pkg 0603LF  page 127 : 1 = P1V05_PCH_STBY_WM26_PLL ; 2 = GND
C2M11  CAP  47UF 4V 20% X6S  pkg 0805  page 131 : 1 = P1V05_PCH_STBY ; 2 = GND
C2M12  CAP_A  22.0UF 4V 20% X6S  pkg 0603V  page 131 : 1 = P1V05_PCH_STBY ; 2 = GND
C2M13  CAP_A  22.0UF 4V 20% X6S  pkg 0603V  page 131 : 1 = P1V05_PCH_STBY ; 2 = GND
C2M14  CAP  0.22UF 16V 10% X7R  pkg 0402  page 106 : 1 = P3E_CPU0_PE3_OCP_TXP<8> ; 2 = P3E_OCP_CPU0_PE3_C_TXP<8>
C2M15  CAP  0.22UF 16V 10% X7R  pkg 0402  page 106 : 1 = P3E_CPU0_PE3_OCP_TXN<8> ; 2 = P3E_OCP_CPU0_PE3_C_TXN<8>
C2M16  CAP_A  1.0UF 6.3V 10% X6S  pkg 0402V  page 130 : 1 = P3V3_STBY ; 2 = GND
C2M17  CAP  47UF 4V 20% X6S  pkg 0805  page 131 : 1 = P1V05_PCH_STBY ; 2 = GND
C2M18  CAP_A  1.0UF 6.3V 10% X6S  pkg 0402V  page 131 : 1 = P1V05_PCH_STBY ; 2 = GND
C2M19  CAP_A  1.0UF 6.3V 10% X6S  pkg 0402V  page 131 : 1 = P1V05_PCH_STBY ; 2 = GND
C2M20  CAP_A  1.0UF 6.3V 10% X6S  pkg 0402V  page 131 : 1 = P1V05_PCH_STBY ; 2 = GND
C2M21  CAP_A  1.0UF 6.3V 10% X6S  pkg 0402V  page 131 : 1 = P1V05_PCH_STBY ; 2 = GND
C2M22  CAP_A  1.0UF 6.3V 10% X6S  pkg 0402V  page 131 : 1 = P1V05_PCH_STBY ; 2 = GND
C2M23  CAP_A  0.1UF 16V 10% X7R  pkg 0402V  page 139 : 1 = PE_PCH_SPRV_TX_DP ; 2 = PE_PCH_SPRV_TX_C_DP
C2M24  CAP_A  0.1UF 16V 10% X7R  pkg 0402V  page 139 : 1 = PE_PCH_SPRV_TX_DN ; 2 = PE_PCH_SPRV_TX_C_DN
C2M25  CAP_A  1.0UF 6.3V 10% X6S  pkg 0402V  page 127 : 1 = P1V05_PCH_STBY ; 2 = GND
C2N2  CAP_A  1.0UF 6.3V 10% X6S  pkg 0402V  page 131 : 1 = P1V05_PCH_STBY ; 2 = GND
C2N3  CAP_A  1.0UF 6.3V 10% X6S  pkg 0402V  page 132 : 1 = PVNN_PCH_STBY ; 2 = GND
C2N4  CAP_A  1.0UF 6.3V 10% X6S  pkg 0402V  page 132 : 1 = PVNN_PCH_STBY ; 2 = GND
C2N5  CAP_A  1.0UF 6.3V 10% X6S  pkg 0402V  page 127 : 1 = P1V05_PCH_STBY_KR_PLL ; 2 = GND
C2N6  CAP  10UF 4V 20% X6S  pkg 0603LF  page 127 : 1 = P1V05_PCH_STBY_KR_PLL ; 2 = GND
C2N7  CAP_A  1.0UF 6.3V 10% X6S  pkg 0402V  page 131 : 1 = P1V05_PCH_STBY ; 2 = GND
C2N8  CAP_A  1.0UF 6.3V 10% X6S  pkg 0402V  page 131 : 1 = P1V05_PCH_STBY ; 2 = GND
C2N9  CAP_A  1.0UF 6.3V 10% X6S  pkg 0402V  page 132 : 1 = PVNN_PCH_STBY ; 2 = GND
C2N10  CAP_A  22.0UF 4V 20% X6S  pkg 0603V  page 131 : 1 = P1V05_PCH_STBY ; 2 = GND
C2N11  CAP_A  1.0UF 6.3V 10% X6S  pkg 0402V  page 132 : 1 = PVNN_PCH_STBY ; 2 = GND
C2N12  CAP_A  1.0UF 6.3V 10% X6S  pkg 0402V  page 132 : 1 = PVNN_PCH_STBY ; 2 = GND
C2N13  CAP_A  1.0UF 6.3V 10% X6S  pkg 0402V  page 131 : 1 = P1V05_PCH_STBY ; 2 = GND
C2N14  CAP  10UF 6.3V 20% X6S  pkg 0603  page 130 : 1 = P3V3_STBY ; 2 = GND
C2N15  CAP_A  1.0UF 6.3V 10% X6S  pkg 0402V  page 130 : 1 = P1V8_PCH_STBY ; 2 = GND
C2N16  CAP_A  1.0UF 6.3V 10% X6S  pkg 0402V  page 130 : 1 = P1V8_PCH_STBY ; 2 = GND
C2N17  CAP  10UF 6.3V 20% X6S  pkg 0603  page 130 : 1 = P3V3_STBY ; 2 = GND
C2N18  CAP_A  1.0UF 6.3V 10% X6S  pkg 0402V  page 130 : 1 = P3V3_STBY ; 2 = GND
C2N19  CAP_A  1.0UF 6.3V 10% X6S  pkg 0402V  page 130 : 1 = P3V3_STBY ; 2 = GND
C2N20  CAP_A  1.0UF 6.3V 10% X6S  pkg 0402V  page 130 : 1 = P3V3_STBY ; 2 = GND
C2N21  CAP  10UF 6.3V 20% X6S  pkg 0603  page 130 : 1 = P3V3_STBY ; 2 = GND
C2N22  CAP  10UF 6.3V 20% X6S  pkg 0603  page 130 : 1 = P3V3_STBY ; 2 = GND
C2N23  CAP  10UF 6.3V 20% X6S  pkg 0603  page 130 : 1 = P3V3_STBY ; 2 = GND
C2N24  CAP  10UF 6.3V 20% X6S  pkg 0603  page 130 : 1 = P3V3_STBY ; 2 = GND
C2N25  CAP_A  1.0UF 6.3V 10% X6S  pkg 0402V  page 130 : 1 = P3V3_STBY ; 2 = GND
C2N26  CAP_A  1.0UF 6.3V 10% X6S  pkg 0402V  page 130 : 1 = P3V3_STBY ; 2 = GND
C2P1  CAP_A  0.1UF 16V 10% X7R  pkg 0402V  page 170 : 1 = P3V3_STBY ; 2 = GND
C2P2  CAP_A  0.1UF 16V 10% X7R  pkg 0402V  page 192 : 1 = P3V3_STBY ; 2 = GND
C2P3  CAP_A  0.1UF 16V 10% X7R  pkg 0402V  page 192 : 1 = P3V3_STBY ; 2 = GND
C2P4  CAP_A  0.1UF 16V 10% X7R  pkg 0402V  page 192 : 1 = P3V3_STBY ; 2 = GND
C2P5  CAP_A  0.1UF 16V 10% X7R  pkg 0402V  page 192 : 1 = P3V3_STBY ; 2 = GND
C2P6  CAP_A  0.1UF 16V 10% X7R  pkg 0402V  page 192 : 1 = P3V3_STBY ; 2 = GND
C2P7  CAP_A  0.1UF 16V 10% X7R  pkg 0402V  page 192 : 1 = P3V3_STBY ; 2 = GND
C2P8  CAP_A  0.01UF 25V 10% X7R  pkg 0402V  page 192 : 1 = P3V3_STBY ; 2 = GND
C2P9  CAP_A  0.1UF 16V 10% X7R  pkg 0402V  page 185 : 1 = P3V3_STBY ; 2 = GND
C2P10  CAP  22UF 16V 10% X6S  pkg 1206LF  page 188 : 1 = P12V_STBY ; 2 = GND
C2P11  CAP_A  0.1UF 16V 10% X7R  pkg 0402V  page 188 : 1 = P12V_STBY ; 2 = GND
C2P12  CAP_A  0.1UF 16V 10% X7R  pkg 0402V  page 188 : 1 = P12V_STBY ; 2 = GND
C2P13  CAP_A  0.1UF 16V 10% X7R  pkg 0402V  page 188 : 1 = P12V_STBY ; 2 = GND
C2P14  CAP_A  0.1UF 16V 10% X7R  pkg 0402V  page 188 : 1 = P12V_STBY ; 2 = GND
C2P15  CAP_A  0.1UF 16V 10% X7R  pkg 0402V  page 188 : 1 = P12V_STBY ; 2 = GND
C2P16  CAP_A  0.1UF 16V 10% X7R  pkg 0402V  page 188 : 1 = P12V_STBY ; 2 = GND
C2R1  CAP_A  0.1UF 16V 10% X7R  pkg 0402V  page 192 : 1 = P3V3_STBY ; 2 = GND
C2R2  CAP_A  0.1UF 16V 10% X7R  pkg 0402V  page 192 : 1 = P3V3_STBY ; 2 = GND
C2R3  CAP_A  0.1UF 16V 10% X7R  pkg 0402V  page 192 : 1 = P3V3_STBY ; 2 = GND
C2R4  CAP_A  0.1UF 16V 10% X7R  pkg 0402V  page 192 : 1 = P3V3_STBY ; 2 = GND
C2R5  CAP_A  0.1UF 16V 10% X7R  pkg 0402V  page 192 : 1 = P3V3_STBY ; 2 = GND
C2R6  CAP  470PF 50V 10% EMPTY  pkg 0402LF  page 181 : 1 = FM_PS_EN ; 2 = GND
C2R7  CAP  0.22UF 16V 10% X7R  pkg 0402  page 106 : 1 = P3E_CPU0_PE3_OCP_TXN<6> ; 2 = P3E_OCP_CPU0_PE3_C_TXN<6>
C2R8  CAP  0.22UF 16V 10% X7R  pkg 0402  page 106 : 1 = P3E_CPU0_PE3_OCP_TXP<6> ; 2 = P3E_OCP_CPU0_PE3_C_TXP<6>
C2R9  CAP  0.22UF 16V 10% X7R  pkg 0402  page 106 : 1 = P3E_CPU0_PE3_OCP_TXN<7> ; 2 = P3E_OCP_CPU0_PE3_C_TXN<7>
C2R10  CAP  0.22UF 16V 10% X7R  pkg 0402  page 106 : 1 = P3E_CPU0_PE3_OCP_TXP<7> ; 2 = P3E_OCP_CPU0_PE3_C_TXP<7>
C2R11  SC4D7U16V3KX-GP  10%  pkg SMD-BCG5  page 240 : 1 = P5V_STBY ; 2 = AGND_P3V3_STBY
C2R12  CAP_A  1.0UF 6.3V 10% X6S  pkg 0402V  page 157 : 1 = FP_NMI_BTN_OUT_N ; 2 = GND
C2R13  CAP  0.22UF 16V 10% X7R  pkg 0402  page 106 : 1 = P3E_CPU0_PE3_OCP_TXN<5> ; 2 = P3E_OCP_CPU0_PE3_C_TXN<5>
C2R14  CAP  0.22UF 16V 10% X7R  pkg 0402  page 106 : 1 = P3E_CPU0_PE3_OCP_TXP<5> ; 2 = P3E_OCP_CPU0_PE3_C_TXP<5>
C2R15  CAP_A  0.1UF 16V 10% X7R  pkg 0402V  page 188 : 1 = P12V_STBY ; 2 = GND
C2R16  CAP_A  0.1UF 16V 10% X7R  pkg 0402V  page 188 : 1 = P12V_STBY ; 2 = GND
C2R17  CAP_A  0.1UF 16V 10% X7R  pkg 0402V  page 188 : 1 = P12V_STBY ; 2 = GND
C2R18  CAP_A  0.1UF 16V 10% X7R  pkg 0402V  page 188 : 1 = P12V_STBY ; 2 = GND
C2T1  CAP_A  0.1UF 16V 10% X7R  pkg 0402V  page 154 : 1 = P3V3_STBY ; 2 = GND
C2T2  CAP_A  0.1UF 16V 10% X7R  pkg 0402V  page 185 : 1 = P3V3 ; 2 = GND
C2T3  CAP_A  0.1UF 16V 10% X7R  pkg 0402V  page 157 : 1 = P3V3_STBY ; 2 = GND
C2T4  CAP_A  0.1UF 16V 10% X7R  pkg 0402V  page 185 : 1 = P3V3 ; 2 = GND
C2T5  CAP_A  0.1UF 16V 10% X7R  pkg 0402V  page 185 : 1 = P3V3 ; 2 = GND
C2T6  CAP  22UF 6.3V 20% X6S  pkg 0805  page 240 : 1 = P3V3_STBY ; 2 = GND
C2T7  CAP  22UF 6.3V 20% X6S  pkg 0805  page 240 : 1 = P3V3_STBY ; 2 = GND
C2T8  CAP_A  0.1UF 16V 10% X7R  pkg 0402V  page 154 : 1 = P3V3_STBY ; 2 = GND
C2T9  CAP  22UF 6.3V 20% X6S  pkg 0805  page 240 : 1 = P3V3_STBY ; 2 = GND
C2T10  CAP  0.22UF 16V 10% X7R  pkg 0402  page 185 : 1 = P3E_PCH_M2_TX_C_DP<1> ; 2 = P3E_PCH_M2_TX_DP<1>
C2T11  CAP  0.22UF 16V 10% X7R  pkg 0402  page 185 : 1 = P3E_PCH_M2_TX_C_DN<1> ; 2 = P3E_PCH_M2_TX_DN<1>
C2T12  CAP_A  0.1UF 16V 10% X7R  pkg 0402V  page 154 : 1 = P3V3_STBY ; 2 = GND
C2T13  CAP  0.22UF 16V 10% X7R  pkg 0402  page 185 : 1 = P3E_PCH_M2_TX_C_DP<2> ; 2 = P3E_PCH_M2_TX_DP<2>
C2T14  CAP  0.22UF 16V 10% X7R  pkg 0402  page 185 : 1 = P3E_PCH_M2_TX_C_DN<2> ; 2 = P3E_PCH_M2_TX_DN<2>
C2T15  CAP_A  0.1UF 16V 10% X7R  pkg 0402V  page 185 : 1 = P3V3 ; 2 = GND
C2T16  CAP_A  0.1UF 16V 10% X7R  pkg 0402V  page 185 : 1 = P3V3 ; 2 = GND
C2T17  CAP_A  0.1UF 16V 10% X7R  pkg 0402V  page 101 : 1 = P3V3_STBY_MNG ; 2 = GND
C2T18  CAP_A  0.01UF 25V 10% X7R  pkg 0402V  page 101 : 1 = P3V3_STBY_MNG_CPU ; 2 = GND
C2T19  CAP_A  1.0UF 6.3V 10% X6S  pkg 0402V  page 101 : 1 = P3V3_STBY_MNG_CPU ; 2 = GND
C2T20  CAP  0.22UF 16V 10% X7R  pkg 0402  page 185 : 1 = P3E_PCH_M2_TX_C_DP<3> ; 2 = P3E_PCH_M2_TX_DP<3>
C2T21  CAP_A  0.1UF 16V 10% X7R  pkg 0402V  page 185 : 1 = P3V3 ; 2 = GND
C2T22  CAP  10UF 16V 10% X6S  pkg 0805  page 101 : 1 = P3V3_STBY_MNG ; 2 = GND
C2T23  CAP  0.22UF 16V 10% X7R  pkg 0402  page 185 : 1 = P3E_PCH_M2_TX_C_DN<3> ; 2 = P3E_PCH_M2_TX_DN<3>
C2T24  CAP_A  0.1UF 16V 10% X7R  pkg 0402V  page 185 : 1 = P3V3 ; 2 = GND
C2T25  CAP_A  0.1UF 16V 10% X7R  pkg 0402V  page 101 : 1 = P3V3_STBY_MNG ; 2 = GND
C2T26  CAP_A  0.1UF 16V 10% X7R  pkg 0402V  page 185 : 1 = P3V3 ; 2 = GND
